(kicad_pcb
	(version 20260206)
	(generator "pcbnew")
	(generator_version "10.0")
	(general
		(thickness 1.6)
		(legacy_teardrops no)
	)
	(paper "A4")
	(title_block
		(title "Bryce Canyon_R.DPB_16317-1_OCP.brd")
		(comment 1 "Bryce Canyon / footprints 1418-1425 of 2099")
	)
	(layers
		(0 "F.Cu" signal "TOP")
		(4 "In1.Cu" signal "L2GND")
		(6 "In2.Cu" signal "L3")
		(8 "In3.Cu" signal "L4VCC")
		(10 "In4.Cu" signal "L5VCC")
		(12 "In5.Cu" signal "L6")
		(14 "In6.Cu" signal "L7GND")
		(2 "B.Cu" signal "BOTTOM")
		(9 "F.Adhes" user "F.Adhesive")
		(11 "B.Adhes" user "B.Adhesive")
		(13 "F.Paste" user "Package Geometry/Pastemask Top")
		(15 "B.Paste" user "Package Geometry/Pastemask Bottom")
		(5 "F.SilkS" user "Ref Des/Silkscreen Top")
		(7 "B.SilkS" user "Ref Des/Silkscreen Bottom")
		(1 "F.Mask" user "Board Geometry/Soldermask Top")
		(3 "B.Mask" user "Board Geometry/Soldermask Bottom")
		(17 "Dwgs.User" user "User.Drawings")
		(19 "Cmts.User" user "User.Comments")
		(21 "Eco1.User" user "User.Eco1")
		(23 "Eco2.User" user "User.Eco2")
		(25 "Edge.Cuts" user "Board Geometry/Outline")
		(27 "Margin" user)
		(31 "F.CrtYd" user "Package Geometry/Place Bound Top")
		(29 "B.CrtYd" user "Package Geometry/Place Bound Bottom")
		(35 "F.Fab" user "Ref Des/Assembly Top")
		(33 "B.Fab" user "Ref Des/Assembly Bottom")
	)
	(footprint ""
		(layer "F.Cu")
		(at 20.1676 -148.717 -90)
		(property "Reference" "C186"
			(at 0 0 270)
			(layer "F.SilkS")
			(hide yes)
			(effects
				(font
					(size 1.27 1.27)
				)
			)
		)
		(property "Value" "SC1U16V3KX-5GP"
			(at 0 -2.8194 270)
			(unlocked yes)
			(layer "F.Fab")
			(hide yes)
			(effects
				(font
					(size 1.016 1.016)
					(thickness 0.1524)
				)
			)
		)
		(property "Device Type" "C603H36"
			(at 0 -4.3434 270)
			(unlocked yes)
			(layer "F.Fab")
			(hide yes)
			(effects
				(font
					(size 1.016 1.016)
					(thickness 0.1524)
				)
			)
		)
		(duplicate_pad_numbers_are_jumpers no)
		(fp_line
			(start 0.508 0)
			(end -0.508 0)
			(stroke
				(width 0.2032)
				(type default)
			)
			(layer "F.SilkS")
		)
		(fp_rect
			(start -0.5842 1.3335)
			(end 0.5842 -1.3335)
			(stroke
				(width 0)
				(type default)
			)
			(fill no)
			(layer "F.CrtYd")
		)
		(fp_rect
			(start -0.5842 1.3335)
			(end 0.5842 -1.3335)
			(stroke
				(width 0)
				(type default)
			)
			(fill no)
			(layer "F.Fab")
		)
		(pad "1" smd custom
			(at 0 -0.762 270)
			(size 0.2159 0.2159)
			(layers "F.Cu" "F.Mask" "F.Paste")
			(net "P5V_HDD12")
			(options
				(clearance outline)
				(anchor circle)
			)
			(primitives
				(gr_poly
					(pts
						(arc
							(start -0.3302 -0.4318)
							(mid -0.402042 -0.402042)
							(end -0.4318 -0.3302)
						)
						(arc
							(start -0.4318 0.3302)
							(mid -0.402042 0.402042)
							(end -0.3302 0.4318)
						)
						(arc
							(start 0.3302 0.4318)
							(mid 0.402042 0.402042)
							(end 0.4318 0.3302)
						)
						(arc
							(start 0.4318 -0.3302)
							(mid 0.402042 -0.402042)
							(end 0.3302 -0.4318)
						)
					)
					(width 0)
					(fill yes)
				)
			)
		)
		(pad "2" smd custom
			(at 0 0.762 270)
			(size 0.2159 0.2159)
			(layers "F.Cu" "F.Mask" "F.Paste")
			(net "GND")
			(options
				(clearance outline)
				(anchor circle)
			)
			(primitives
				(gr_poly
					(pts
						(arc
							(start -0.3302 -0.4318)
							(mid -0.402042 -0.402042)
							(end -0.4318 -0.3302)
						)
						(arc
							(start -0.4318 0.3302)
							(mid -0.402042 0.402042)
							(end -0.3302 0.4318)
						)
						(arc
							(start 0.3302 0.4318)
							(mid 0.402042 0.402042)
							(end 0.4318 0.3302)
						)
						(arc
							(start 0.4318 -0.3302)
							(mid 0.402042 -0.402042)
							(end 0.3302 -0.4318)
						)
					)
					(width 0)
					(fill yes)
				)
			)
		)
	)
	(footprint ""
		(layer "F.Cu")
		(at 97.385632 -244.990874 90)
		(property "Reference" "VIA5"
			(at 0 0 90)
			(layer "F.SilkS")
			(hide yes)
			(effects
				(font
					(size 1.27 1.27)
				)
			)
		)
		(property "Value" "100OHM-8L-2D36MM-L18-GP"
			(at 3.8989 0.5715 90)
			(unlocked yes)
			(layer "F.Fab")
			(hide yes)
			(effects
				(font
					(size 1.016 1.016)
					(thickness 0.1524)
				)
			)
		)
		(property "Device Type" "VIA-PCIE-4P-414097"
			(at 3.8989 -0.9525 90)
			(unlocked yes)
			(layer "F.Fab")
			(hide yes)
			(effects
				(font
					(size 1.016 1.016)
					(thickness 0.1524)
				)
			)
		)
		(duplicate_pad_numbers_are_jumpers no)
		(fp_rect
			(start -2.0701 0.4826)
			(end 2.0701 -0.4826)
			(stroke
				(width 0)
				(type default)
			)
			(fill no)
			(layer "F.CrtYd")
		)
		(fp_rect
			(start -2.0701 0.4826)
			(end 2.0701 -0.4826)
			(stroke
				(width 0)
				(type default)
			)
			(fill no)
			(layer "F.Fab")
		)
		(pad "1" thru_hole circle
			(at -1.5875 0 90)
			(size 0.508 0.508)
			(drill 0.254)
			(layers "*.Cu" "*.Mask")
			(remove_unused_layers no)
			(net "GND")
			(clearance 0.2286)
			(thermal_gap 0.2286)
		)
		(pad "2" thru_hole circle
			(at -0.5715 0 90)
			(size 0.508 0.508)
			(drill 0.254)
			(layers "*.Cu" "*.Mask")
			(remove_unused_layers no)
			(net "PHY_SCC_B_TO_DRV_B_2_DP")
			(clearance 0.2286)
			(thermal_gap 0.2286)
		)
		(pad "3" thru_hole circle
			(at 0.5715 0 90)
			(size 0.508 0.508)
			(drill 0.254)
			(layers "*.Cu" "*.Mask")
			(remove_unused_layers no)
			(net "PHY_SCC_B_TO_DRV_B_2_DN")
			(clearance 0.2286)
			(thermal_gap 0.2286)
		)
		(pad "4" thru_hole circle
			(at 1.5875 0 90)
			(size 0.508 0.508)
			(drill 0.254)
			(layers "*.Cu" "*.Mask")
			(remove_unused_layers no)
			(net "GND")
			(clearance 0.2286)
			(thermal_gap 0.2286)
		)
	)
	(footprint ""
		(layer "F.Cu")
		(at 48.26 -138.049 90)
		(property "Reference" "R376"
			(at 0 0 90)
			(layer "F.SilkS")
			(hide yes)
			(effects
				(font
					(size 1.27 1.27)
				)
			)
		)
		(property "Value" "4K7R2J-2-GP"
			(at 0.064008 -3.993896 90)
			(unlocked yes)
			(layer "F.Fab")
			(hide yes)
			(effects
				(font
					(size 1.016 1.016)
					(thickness 0.1524)
				)
			)
		)
		(property "Device Type" "R402H16"
			(at 0.064008 -5.517896 90)
			(unlocked yes)
			(layer "F.Fab")
			(hide yes)
			(effects
				(font
					(size 1.016 1.016)
					(thickness 0.1524)
				)
			)
		)
		(duplicate_pad_numbers_are_jumpers no)
		(fp_line
			(start 0.508 -0.9398)
			(end -0.508 -0.9398)
			(stroke
				(width 0.1524)
				(type default)
			)
			(layer "F.SilkS")
		)
		(fp_line
			(start -0.508 -0.9398)
			(end -0.508 0.9398)
			(stroke
				(width 0.1524)
				(type default)
			)
			(layer "F.SilkS")
		)
		(fp_rect
			(start -0.508 0.9398)
			(end 0.508 -0.9398)
			(stroke
				(width 0)
				(type default)
			)
			(fill no)
			(layer "F.CrtYd")
		)
		(fp_rect
			(start -0.508 0.9398)
			(end 0.508 -0.9398)
			(stroke
				(width 0)
				(type default)
			)
			(fill no)
			(layer "F.Fab")
		)
		(pad "1" smd custom
			(at 0 -0.4445 90)
			(size 0.1397 0.1397)
			(layers "F.Cu" "F.Mask" "F.Paste")
			(net "P12V_B")
			(options
				(clearance outline)
				(anchor circle)
			)
			(primitives
				(gr_poly
					(pts
						(arc
							(start -0.1778 -0.2794)
							(mid -0.249642 -0.249642)
							(end -0.2794 -0.1778)
						)
						(arc
							(start -0.2794 0.1778)
							(mid -0.249642 0.249642)
							(end -0.1778 0.2794)
						)
						(arc
							(start 0.1778 0.2794)
							(mid 0.249642 0.249642)
							(end 0.2794 0.1778)
						)
						(arc
							(start 0.2794 -0.1778)
							(mid 0.249642 -0.249642)
							(end 0.1778 -0.2794)
						)
					)
					(width 0)
					(fill yes)
				)
			)
		)
		(pad "2" smd custom
			(at 0 0.4445 90)
			(size 0.1397 0.1397)
			(layers "F.Cu" "F.Mask" "F.Paste")
			(net "SW_HDD_P13")
			(options
				(clearance outline)
				(anchor circle)
			)
			(primitives
				(gr_poly
					(pts
						(arc
							(start -0.1778 -0.2794)
							(mid -0.249642 -0.249642)
							(end -0.2794 -0.1778)
						)
						(arc
							(start -0.2794 0.1778)
							(mid -0.249642 0.249642)
							(end -0.1778 0.2794)
						)
						(arc
							(start 0.1778 0.2794)
							(mid 0.249642 0.249642)
							(end 0.2794 0.1778)
						)
						(arc
							(start 0.2794 -0.1778)
							(mid 0.249642 -0.249642)
							(end 0.1778 -0.2794)
						)
					)
					(width 0)
					(fill yes)
				)
			)
		)
	)
	(footprint ""
		(layer "F.Cu")
		(at 127.15875 -248.750074 -90)
		(property "Reference" "VIA8"
			(at 0 0 270)
			(layer "F.SilkS")
			(hide yes)
			(effects
				(font
					(size 1.27 1.27)
				)
			)
		)
		(property "Value" "100OHM-8L-2D36MM-L16-GP"
			(at -3.4036 -0.4572 270)
			(unlocked yes)
			(layer "F.Fab")
			(hide yes)
			(effects
				(font
					(size 1.016 1.016)
					(thickness 0.1524)
				)
			)
		)
		(property "Device Type" "VIA-PCIE-4P-427097"
			(at -3.4036 -1.9812 270)
			(unlocked yes)
			(layer "F.Fab")
			(hide yes)
			(effects
				(font
					(size 1.016 1.016)
					(thickness 0.1524)
				)
			)
		)
		(duplicate_pad_numbers_are_jumpers no)
		(fp_rect
			(start -2.1336 0.4826)
			(end 2.1336 -0.4826)
			(stroke
				(width 0)
				(type default)
			)
			(fill no)
			(layer "F.CrtYd")
		)
		(fp_rect
			(start -2.1336 0.4826)
			(end 2.1336 -0.4826)
			(stroke
				(width 0)
				(type default)
			)
			(fill no)
			(layer "F.Fab")
		)
		(pad "1" thru_hole circle
			(at -1.651 0 270)
			(size 0.508 0.508)
			(drill 0.254)
			(layers "*.Cu" "*.Mask")
			(remove_unused_layers no)
			(net "GND")
			(clearance 0.2286)
			(thermal_gap 0.2286)
		)
		(pad "2" thru_hole circle
			(at -0.635 0 270)
			(size 0.508 0.508)
			(drill 0.254)
			(layers "*.Cu" "*.Mask")
			(remove_unused_layers no)
			(net "PHY_DRV_B_TO_SCC_B_3_DP")
			(clearance 0.2286)
			(thermal_gap 0.2286)
		)
		(pad "3" thru_hole circle
			(at 0.635 0 270)
			(size 0.508 0.508)
			(drill 0.254)
			(layers "*.Cu" "*.Mask")
			(remove_unused_layers no)
			(net "PHY_DRV_B_TO_SCC_B_3_DN")
			(clearance 0.2286)
			(thermal_gap 0.2286)
		)
		(pad "4" thru_hole circle
			(at 1.651 0 270)
			(size 0.508 0.508)
			(drill 0.254)
			(layers "*.Cu" "*.Mask")
			(remove_unused_layers no)
			(net "GND")
			(clearance 0.2286)
			(thermal_gap 0.2286)
		)
	)
	(footprint ""
		(layer "F.Cu")
		(at 386.6896 -248.750074 -90)
		(property "Reference" "VIA18"
			(at 0 0 270)
			(layer "F.SilkS")
			(hide yes)
			(effects
				(font
					(size 1.27 1.27)
				)
			)
		)
		(property "Value" "100OHM-8L-2D36MM-L16-GP"
			(at -3.4036 -0.4572 270)
			(unlocked yes)
			(layer "F.Fab")
			(hide yes)
			(effects
				(font
					(size 1.016 1.016)
					(thickness 0.1524)
				)
			)
		)
		(property "Device Type" "VIA-PCIE-4P-427097"
			(at -3.4036 -1.9812 270)
			(unlocked yes)
			(layer "F.Fab")
			(hide yes)
			(effects
				(font
					(size 1.016 1.016)
					(thickness 0.1524)
				)
			)
		)
		(duplicate_pad_numbers_are_jumpers no)
		(fp_rect
			(start -2.1336 0.4826)
			(end 2.1336 -0.4826)
			(stroke
				(width 0)
				(type default)
			)
			(fill no)
			(layer "F.CrtYd")
		)
		(fp_rect
			(start -2.1336 0.4826)
			(end 2.1336 -0.4826)
			(stroke
				(width 0)
				(type default)
			)
			(fill no)
			(layer "F.Fab")
		)
		(pad "1" thru_hole circle
			(at -1.651 0 270)
			(size 0.508 0.508)
			(drill 0.254)
			(layers "*.Cu" "*.Mask")
			(remove_unused_layers no)
			(net "GND")
			(clearance 0.2286)
			(thermal_gap 0.2286)
		)
		(pad "2" thru_hole circle
			(at -0.635 0 270)
			(size 0.508 0.508)
			(drill 0.254)
			(layers "*.Cu" "*.Mask")
			(remove_unused_layers no)
			(net "PHY_DRV_B_TO_SCC_B_8_DP")
			(clearance 0.2286)
			(thermal_gap 0.2286)
		)
		(pad "3" thru_hole circle
			(at 0.635 0 270)
			(size 0.508 0.508)
			(drill 0.254)
			(layers "*.Cu" "*.Mask")
			(remove_unused_layers no)
			(net "PHY_DRV_B_TO_SCC_B_8_DN")
			(clearance 0.2286)
			(thermal_gap 0.2286)
		)
		(pad "4" thru_hole circle
			(at 1.651 0 270)
			(size 0.508 0.508)
			(drill 0.254)
			(layers "*.Cu" "*.Mask")
			(remove_unused_layers no)
			(net "GND")
			(clearance 0.2286)
			(thermal_gap 0.2286)
		)
	)
	(footprint ""
		(layer "F.Cu")
		(at 326.992996 -364.236 -90)
		(property "Reference" "R951"
			(at 0 0 270)
			(layer "F.SilkS")
			(hide yes)
			(effects
				(font
					(size 1.27 1.27)
				)
			)
		)
		(property "Value" "10KR2F-2-GP"
			(at 0.064008 -3.993896 270)
			(unlocked yes)
			(layer "F.Fab")
			(hide yes)
			(effects
				(font
					(size 1.016 1.016)
					(thickness 0.1524)
				)
			)
		)
		(property "Device Type" "R402H16"
			(at 0.064008 -5.517896 270)
			(unlocked yes)
			(layer "F.Fab")
			(hide yes)
			(effects
				(font
					(size 1.016 1.016)
					(thickness 0.1524)
				)
			)
		)
		(duplicate_pad_numbers_are_jumpers no)
		(fp_line
			(start -0.508 -0.9398)
			(end -0.508 0.9398)
			(stroke
				(width 0.1524)
				(type default)
			)
			(layer "F.SilkS")
		)
		(fp_line
			(start 0.508 -0.9398)
			(end -0.508 -0.9398)
			(stroke
				(width 0.1524)
				(type default)
			)
			(layer "F.SilkS")
		)
		(fp_rect
			(start -0.508 0.9398)
			(end 0.508 -0.9398)
			(stroke
				(width 0)
				(type default)
			)
			(fill no)
			(layer "F.CrtYd")
		)
		(fp_rect
			(start -0.508 0.9398)
			(end 0.508 -0.9398)
			(stroke
				(width 0)
				(type default)
			)
			(fill no)
			(layer "F.Fab")
		)
		(pad "1" smd custom
			(at 0 -0.4445 270)
			(size 0.1397 0.1397)
			(layers "F.Cu" "F.Mask" "F.Paste")
			(net "GND")
			(options
				(clearance outline)
				(anchor circle)
			)
			(primitives
				(gr_poly
					(pts
						(arc
							(start -0.1778 -0.2794)
							(mid -0.249642 -0.249642)
							(end -0.2794 -0.1778)
						)
						(arc
							(start -0.2794 0.1778)
							(mid -0.249642 0.249642)
							(end -0.1778 0.2794)
						)
						(arc
							(start 0.1778 0.2794)
							(mid 0.249642 0.249642)
							(end 0.2794 0.1778)
						)
						(arc
							(start 0.2794 -0.1778)
							(mid 0.249642 -0.249642)
							(end 0.1778 -0.2794)
						)
					)
					(width 0)
					(fill yes)
				)
			)
		)
		(pad "2" smd custom
			(at 0 0.4445 270)
			(size 0.1397 0.1397)
			(layers "F.Cu" "F.Mask" "F.Paste")
			(net "FANTACH_F2")
			(options
				(clearance outline)
				(anchor circle)
			)
			(primitives
				(gr_poly
					(pts
						(arc
							(start -0.1778 -0.2794)
							(mid -0.249642 -0.249642)
							(end -0.2794 -0.1778)
						)
						(arc
							(start -0.2794 0.1778)
							(mid -0.249642 0.249642)
							(end -0.1778 0.2794)
						)
						(arc
							(start 0.1778 0.2794)
							(mid 0.249642 0.249642)
							(end 0.2794 0.1778)
						)
						(arc
							(start 0.2794 -0.1778)
							(mid 0.249642 -0.249642)
							(end 0.1778 -0.2794)
						)
					)
					(width 0)
					(fill yes)
				)
			)
		)
	)
	(footprint ""
		(layer "F.Cu")
		(at 430.403 -246.761 180)
		(property "Reference" "R315"
			(at 0 0 180)
			(layer "F.SilkS")
			(hide yes)
			(effects
				(font
					(size 1.27 1.27)
				)
			)
		)
		(property "Value" "0R2J-2-GP"
			(at 0.064008 -3.993896 180)
			(unlocked yes)
			(layer "F.Fab")
			(hide yes)
			(effects
				(font
					(size 1.016 1.016)
					(thickness 0.1524)
				)
			)
		)
		(property "Device Type" "R402H16"
			(at 0.064008 -5.517896 180)
			(unlocked yes)
			(layer "F.Fab")
			(hide yes)
			(effects
				(font
					(size 1.016 1.016)
					(thickness 0.1524)
				)
			)
		)
		(duplicate_pad_numbers_are_jumpers no)
		(fp_line
			(start 0.508 -0.9398)
			(end -0.508 -0.9398)
			(stroke
				(width 0.1524)
				(type default)
			)
			(layer "F.SilkS")
		)
		(fp_line
			(start -0.508 -0.9398)
			(end -0.508 0.9398)
			(stroke
				(width 0.1524)
				(type default)
			)
			(layer "F.SilkS")
		)
		(fp_rect
			(start -0.508 0.9398)
			(end 0.508 -0.9398)
			(stroke
				(width 0)
				(type default)
			)
			(fill no)
			(layer "F.CrtYd")
		)
		(fp_rect
			(start -0.508 0.9398)
			(end 0.508 -0.9398)
			(stroke
				(width 0)
				(type default)
			)
			(fill no)
			(layer "F.Fab")
		)
		(pad "1" smd custom
			(at 0 -0.4445 180)
			(size 0.1397 0.1397)
			(layers "F.Cu" "F.Mask" "F.Paste")
			(net "SW_HDD_G9")
			(options
				(clearance outline)
				(anchor circle)
			)
			(primitives
				(gr_poly
					(pts
						(arc
							(start -0.1778 -0.2794)
							(mid -0.249642 -0.249642)
							(end -0.2794 -0.1778)
						)
						(arc
							(start -0.2794 0.1778)
							(mid -0.249642 0.249642)
							(end -0.1778 0.2794)
						)
						(arc
							(start 0.1778 0.2794)
							(mid 0.249642 0.249642)
							(end 0.2794 0.1778)
						)
						(arc
							(start 0.2794 -0.1778)
							(mid 0.249642 -0.249642)
							(end 0.1778 -0.2794)
						)
					)
					(width 0)
					(fill yes)
				)
			)
		)
		(pad "2" smd custom
			(at 0 0.4445 180)
			(size 0.1397 0.1397)
			(layers "F.Cu" "F.Mask" "F.Paste")
			(net "SW_HDD_R9")
			(options
				(clearance outline)
				(anchor circle)
			)
			(primitives
				(gr_poly
					(pts
						(arc
							(start -0.1778 -0.2794)
							(mid -0.249642 -0.249642)
							(end -0.2794 -0.1778)
						)
						(arc
							(start -0.2794 0.1778)
							(mid -0.249642 0.249642)
							(end -0.1778 0.2794)
						)
						(arc
							(start 0.1778 0.2794)
							(mid 0.249642 0.249642)
							(end 0.2794 0.1778)
						)
						(arc
							(start 0.2794 -0.1778)
							(mid 0.249642 -0.249642)
							(end 0.1778 -0.2794)
						)
					)
					(width 0)
					(fill yes)
				)
			)
		)
	)
	(footprint ""
		(layer "F.Cu")
		(at 362.966 -262.001 -90)
		(property "Reference" "R270"
			(at 0 0 270)
			(layer "F.SilkS")
			(hide yes)
			(effects
				(font
					(size 1.27 1.27)
				)
			)
		)
		(property "Value" "2R6F-GP"
			(at -0.0508 -4.8514 270)
			(unlocked yes)
			(layer "F.Fab")
			(hide yes)
			(effects
				(font
					(size 1.016 1.016)
					(thickness 0.1524)
				)
			)
		)
		(property "Device Type" "R1206H26"
			(at 0 -6.3754 270)
			(unlocked yes)
			(layer "F.Fab")
			(hide yes)
			(effects
				(font
					(size 1.016 1.016)
					(thickness 0.1524)
				)
			)
		)
		(duplicate_pad_numbers_are_jumpers no)
		(fp_line
			(start -1.016 2.2352)
			(end -1.016 -2.2352)
			(stroke
				(width 0.1524)
				(type default)
			)
			(layer "F.SilkS")
		)
		(fp_line
			(start 1.016 2.2352)
			(end -1.016 2.2352)
			(stroke
				(width 0.1524)
				(type default)
			)
			(layer "F.SilkS")
		)
		(fp_line
			(start -1.016 -2.2352)
			(end 1.016 -2.2352)
			(stroke
				(width 0.1524)
				(type default)
			)
			(layer "F.SilkS")
		)
		(fp_line
			(start 1.016 -2.2352)
			(end 1.016 2.2352)
			(stroke
				(width 0.1524)
				(type default)
			)
			(layer "F.SilkS")
		)
		(fp_rect
			(start -1.0922 2.3114)
			(end 1.0922 -2.3114)
			(stroke
				(width 0)
				(type default)
			)
			(fill no)
			(layer "F.CrtYd")
		)
		(fp_poly
			(pts
				(xy -1.0922 -2.3114) (xy 1.0922 -2.3114) (xy 1.0922 2.3114) (xy -1.0922 2.3114)
			)
			(stroke
				(width 0)
				(type default)
			)
			(fill no)
			(layer "F.Fab")
		)
		(pad "1" smd rect
			(at 0 -1.397 270)
			(size 1.651 1.27)
			(layers "F.Cu" "F.Mask" "F.Paste")
			(net "P5V_HDD7")
		)
		(pad "2" smd rect
			(at 0 1.397 270)
			(size 1.651 1.27)
			(layers "F.Cu" "F.Mask" "F.Paste")
			(net "5V_PRE_7")
		)
	)
)
